(kicad_pcb
	(version 20260206)
	(generator "pcbnew")
	(generator_version "10.0")
	(general
		(thickness 1.6)
		(legacy_teardrops no)
	)
	(paper "A4")
	(title_block
		(title "Bryce Canyon_IOM_IOC_16318-2_OCP.brd")
		(comment 1 "Bryce Canyon / footprints 1064-1072 of 1605")
	)
	(layers
		(0 "F.Cu" signal "TOP")
		(4 "In1.Cu" signal "L2GND")
		(6 "In2.Cu" signal "L3")
		(8 "In3.Cu" signal "L4VCC")
		(10 "In4.Cu" signal "L5VCC")
		(12 "In5.Cu" signal "L6")
		(14 "In6.Cu" signal "L7GND")
		(2 "B.Cu" signal "BOTTOM")
		(9 "F.Adhes" user "F.Adhesive")
		(11 "B.Adhes" user "B.Adhesive")
		(13 "F.Paste" user "Package Geometry/Pastemask Top")
		(15 "B.Paste" user "Package Geometry/Pastemask Bottom")
		(5 "F.SilkS" user "Ref Des/Silkscreen Top")
		(7 "B.SilkS" user "Ref Des/Silkscreen Bottom")
		(1 "F.Mask" user "Board Geometry/Soldermask Top")
		(3 "B.Mask" user "Board Geometry/Soldermask Bottom")
		(17 "Dwgs.User" user "User.Drawings")
		(19 "Cmts.User" user "User.Comments")
		(21 "Eco1.User" user "User.Eco1")
		(23 "Eco2.User" user "User.Eco2")
		(25 "Edge.Cuts" user "Board Geometry/Outline")
		(27 "Margin" user)
		(31 "F.CrtYd" user "Package Geometry/Place Bound Top")
		(29 "B.CrtYd" user "Package Geometry/Place Bound Bottom")
		(35 "F.Fab" user "Ref Des/Assembly Top")
		(33 "B.Fab" user "Ref Des/Assembly Bottom")
	)
	(footprint ""
		(layer "B.Cu")
		(at 189.8396 -52.959 -90)
		(property "Reference" "R666"
			(at 0 0 90)
			(layer "B.SilkS")
			(hide yes)
			(effects
				(font
					(size 1.27 1.27)
				)
				(justify mirror)
			)
		)
		(property "Value" "10KR2F-2-GP"
			(at -0.064008 -3.993896 270)
			(unlocked yes)
			(layer "B.Fab")
			(hide yes)
			(effects
				(font
					(size 1.016 1.016)
					(thickness 0.1524)
				)
				(justify mirror)
			)
		)
		(property "Device Type" "R402H16"
			(at -0.064008 -5.517896 270)
			(unlocked yes)
			(layer "B.Fab")
			(hide yes)
			(effects
				(font
					(size 1.016 1.016)
					(thickness 0.1524)
				)
				(justify mirror)
			)
		)
		(duplicate_pad_numbers_are_jumpers no)
		(fp_line
			(start -0.508 -0.9398)
			(end 0.508 -0.9398)
			(stroke
				(width 0.1524)
				(type default)
			)
			(layer "B.SilkS")
		)
		(fp_line
			(start 0.508 -0.9398)
			(end 0.508 0.9398)
			(stroke
				(width 0.1524)
				(type default)
			)
			(layer "B.SilkS")
		)
		(fp_rect
			(start 0.508 0.9398)
			(end -0.508 -0.9398)
			(stroke
				(width 0)
				(type default)
			)
			(fill no)
			(layer "B.CrtYd")
		)
		(fp_rect
			(start 0.508 0.9398)
			(end -0.508 -0.9398)
			(stroke
				(width 0)
				(type default)
			)
			(fill no)
			(layer "B.Fab")
		)
		(pad "1" smd custom
			(at 0 -0.4445 90)
			(size 0.1397 0.1397)
			(layers "B.Cu" "B.Mask" "B.Paste")
			(net "P1V8")
			(options
				(clearance outline)
				(anchor circle)
			)
			(primitives
				(gr_poly
					(pts
						(arc
							(start -0.1778 0.2794)
							(mid -0.249642 0.249642)
							(end -0.2794 0.1778)
						)
						(arc
							(start -0.2794 -0.1778)
							(mid -0.249642 -0.249642)
							(end -0.1778 -0.2794)
						)
						(arc
							(start 0.1778 -0.2794)
							(mid 0.249642 -0.249642)
							(end 0.2794 -0.1778)
						)
						(arc
							(start 0.2794 0.1778)
							(mid 0.249642 0.249642)
							(end 0.1778 0.2794)
						)
					)
					(width 0)
					(fill yes)
				)
			)
		)
		(pad "2" smd custom
			(at 0 0.4445 90)
			(size 0.1397 0.1397)
			(layers "B.Cu" "B.Mask" "B.Paste")
			(net "XM_NAND_CS_N")
			(options
				(clearance outline)
				(anchor circle)
			)
			(primitives
				(gr_poly
					(pts
						(arc
							(start -0.1778 0.2794)
							(mid -0.249642 0.249642)
							(end -0.2794 0.1778)
						)
						(arc
							(start -0.2794 -0.1778)
							(mid -0.249642 -0.249642)
							(end -0.1778 -0.2794)
						)
						(arc
							(start 0.1778 -0.2794)
							(mid 0.249642 -0.249642)
							(end 0.2794 -0.1778)
						)
						(arc
							(start 0.2794 0.1778)
							(mid 0.249642 0.249642)
							(end 0.1778 0.2794)
						)
					)
					(width 0)
					(fill yes)
				)
			)
		)
	)
	(footprint ""
		(layer "B.Cu")
		(at 25.3238 -180.8988 -90)
		(property "Reference" "R483"
			(at 0 0 90)
			(layer "B.SilkS")
			(hide yes)
			(effects
				(font
					(size 1.27 1.27)
				)
				(justify mirror)
			)
		)
		(property "Value" "2D2R3J-2-GP"
			(at 0.0254 -2.5146 270)
			(unlocked yes)
			(layer "B.Fab")
			(hide yes)
			(effects
				(font
					(size 1.016 1.016)
					(thickness 0.1524)
				)
				(justify mirror)
			)
		)
		(property "Device Type" "R603H22"
			(at 0.0254 -4.0386 270)
			(unlocked yes)
			(layer "B.Fab")
			(hide yes)
			(effects
				(font
					(size 1.016 1.016)
					(thickness 0.1524)
				)
				(justify mirror)
			)
		)
		(duplicate_pad_numbers_are_jumpers no)
		(fp_line
			(start -0.2032 0)
			(end -0.4826 0)
			(stroke
				(width 0.2032)
				(type default)
			)
			(layer "B.SilkS")
		)
		(fp_line
			(start 0.4826 0)
			(end 0.2032 0)
			(stroke
				(width 0.2032)
				(type default)
			)
			(layer "B.SilkS")
		)
		(fp_rect
			(start 0.5842 1.3335)
			(end -0.5842 -1.3335)
			(stroke
				(width 0)
				(type default)
			)
			(fill no)
			(layer "B.CrtYd")
		)
		(fp_rect
			(start 0.5842 1.3335)
			(end -0.5842 -1.3335)
			(stroke
				(width 0)
				(type default)
			)
			(fill no)
			(layer "B.Fab")
		)
		(pad "1" smd custom
			(at 0 -0.762 90)
			(size 0.2159 0.2159)
			(layers "B.Cu" "B.Mask" "B.Paste")
			(net "P12V_STBY_VDD_PU2")
			(options
				(clearance outline)
				(anchor circle)
			)
			(primitives
				(gr_poly
					(pts
						(arc
							(start -0.3302 0.4318)
							(mid -0.402042 0.402042)
							(end -0.4318 0.3302)
						)
						(arc
							(start -0.4318 -0.3302)
							(mid -0.402042 -0.402042)
							(end -0.3302 -0.4318)
						)
						(arc
							(start 0.3302 -0.4318)
							(mid 0.402042 -0.402042)
							(end 0.4318 -0.3302)
						)
						(arc
							(start 0.4318 0.3302)
							(mid 0.402042 0.402042)
							(end 0.3302 0.4318)
						)
					)
					(width 0)
					(fill yes)
				)
			)
		)
		(pad "2" smd custom
			(at 0 0.762 90)
			(size 0.2159 0.2159)
			(layers "B.Cu" "B.Mask" "B.Paste")
			(net "P12V_STBY")
			(options
				(clearance outline)
				(anchor circle)
			)
			(primitives
				(gr_poly
					(pts
						(arc
							(start -0.3302 0.4318)
							(mid -0.402042 0.402042)
							(end -0.4318 0.3302)
						)
						(arc
							(start -0.4318 -0.3302)
							(mid -0.402042 -0.402042)
							(end -0.3302 -0.4318)
						)
						(arc
							(start 0.3302 -0.4318)
							(mid 0.402042 -0.402042)
							(end 0.4318 -0.3302)
						)
						(arc
							(start 0.4318 0.3302)
							(mid 0.402042 0.402042)
							(end 0.3302 0.4318)
						)
					)
					(width 0)
					(fill yes)
				)
			)
		)
	)
	(footprint ""
		(layer "B.Cu")
		(at 57.1246 -151.6888 -90)
		(property "Reference" "R383"
			(at 0 0 90)
			(layer "B.SilkS")
			(hide yes)
			(effects
				(font
					(size 1.27 1.27)
				)
				(justify mirror)
			)
		)
		(property "Value" "4K7R2F-GP"
			(at -0.064008 -3.993896 270)
			(unlocked yes)
			(layer "B.Fab")
			(hide yes)
			(effects
				(font
					(size 1.016 1.016)
					(thickness 0.1524)
				)
				(justify mirror)
			)
		)
		(property "Device Type" "R402H16"
			(at -0.064008 -5.517896 270)
			(unlocked yes)
			(layer "B.Fab")
			(hide yes)
			(effects
				(font
					(size 1.016 1.016)
					(thickness 0.1524)
				)
				(justify mirror)
			)
		)
		(duplicate_pad_numbers_are_jumpers no)
		(fp_line
			(start -0.508 -0.9398)
			(end 0.508 -0.9398)
			(stroke
				(width 0.1524)
				(type default)
			)
			(layer "B.SilkS")
		)
		(fp_line
			(start 0.508 -0.9398)
			(end 0.508 0.9398)
			(stroke
				(width 0.1524)
				(type default)
			)
			(layer "B.SilkS")
		)
		(fp_rect
			(start 0.508 0.9398)
			(end -0.508 -0.9398)
			(stroke
				(width 0)
				(type default)
			)
			(fill no)
			(layer "B.CrtYd")
		)
		(fp_rect
			(start 0.508 0.9398)
			(end -0.508 -0.9398)
			(stroke
				(width 0)
				(type default)
			)
			(fill no)
			(layer "B.Fab")
		)
		(pad "1" smd custom
			(at 0 -0.4445 90)
			(size 0.1397 0.1397)
			(layers "B.Cu" "B.Mask" "B.Paste")
			(net "P3V3_STBY")
			(options
				(clearance outline)
				(anchor circle)
			)
			(primitives
				(gr_poly
					(pts
						(arc
							(start -0.1778 0.2794)
							(mid -0.249642 0.249642)
							(end -0.2794 0.1778)
						)
						(arc
							(start -0.2794 -0.1778)
							(mid -0.249642 -0.249642)
							(end -0.1778 -0.2794)
						)
						(arc
							(start 0.1778 -0.2794)
							(mid 0.249642 -0.249642)
							(end 0.2794 -0.1778)
						)
						(arc
							(start 0.2794 0.1778)
							(mid 0.249642 0.249642)
							(end 0.1778 0.2794)
						)
					)
					(width 0)
					(fill yes)
				)
			)
		)
		(pad "2" smd custom
			(at 0 0.4445 90)
			(size 0.1397 0.1397)
			(layers "B.Cu" "B.Mask" "B.Paste")
			(net "MAC1_TXD2")
			(options
				(clearance outline)
				(anchor circle)
			)
			(primitives
				(gr_poly
					(pts
						(arc
							(start -0.1778 0.2794)
							(mid -0.249642 0.249642)
							(end -0.2794 0.1778)
						)
						(arc
							(start -0.2794 -0.1778)
							(mid -0.249642 -0.249642)
							(end -0.1778 -0.2794)
						)
						(arc
							(start 0.1778 -0.2794)
							(mid 0.249642 -0.249642)
							(end 0.2794 -0.1778)
						)
						(arc
							(start 0.2794 0.1778)
							(mid 0.249642 0.249642)
							(end 0.1778 0.2794)
						)
					)
					(width 0)
					(fill yes)
				)
			)
		)
	)
	(footprint ""
		(layer "B.Cu")
		(at 207.3656 -59.9186)
		(property "Reference" "TP124"
			(at 0 0 0)
			(layer "B.SilkS")
			(hide yes)
			(effects
				(font
					(size 1.27 1.27)
				)
				(justify mirror)
			)
		)
		(property "Value" "TPAD28-2-GP"
			(at 0.0127 -1.6637 0)
			(unlocked yes)
			(layer "B.Fab")
			(hide yes)
			(effects
				(font
					(size 1.016 1.016)
					(thickness 0.1524)
				)
				(justify mirror)
			)
		)
		(property "Device Type" "TPAD28"
			(at 0.0127 -3.1877 0)
			(unlocked yes)
			(layer "B.Fab")
			(hide yes)
			(effects
				(font
					(size 1.016 1.016)
					(thickness 0.1524)
				)
				(justify mirror)
			)
		)
		(duplicate_pad_numbers_are_jumpers no)
		(fp_poly
			(pts
				(arc
					(start 0.3556 0)
					(mid -0.3556 0)
					(end 0.3556 0)
				)
			)
			(stroke
				(width 0)
				(type default)
			)
			(fill no)
			(layer "B.CrtYd")
		)
		(fp_poly
			(pts
				(arc
					(start 0.6096 0)
					(mid -0.6096 0)
					(end 0.6096 0)
				)
			)
			(stroke
				(width 0)
				(type default)
			)
			(fill no)
			(layer "B.Fab")
		)
		(pad "1" smd circle
			(at 0 0 180)
			(size 0.7112 0.7112)
			(layers "B.Cu" "B.Mask" "B.Paste")
			(net "SIO_DOUT_1")
		)
	)
	(footprint ""
		(layer "B.Cu")
		(at 185.2041 -72.18934 90)
		(property "Reference" "C469"
			(at 0 0 90)
			(layer "B.SilkS")
			(hide yes)
			(effects
				(font
					(size 1.27 1.27)
				)
				(justify mirror)
			)
		)
		(property "Value" "SCD1U16V2KX-3GP"
			(at -1.1811 -2.7051 90)
			(unlocked yes)
			(layer "B.Fab")
			(hide yes)
			(effects
				(font
					(size 1.016 1.016)
					(thickness 0.1524)
				)
				(justify mirror)
			)
		)
		(property "Device Type" "C402H22"
			(at -1.1811 -4.2291 90)
			(unlocked yes)
			(layer "B.Fab")
			(hide yes)
			(effects
				(font
					(size 1.016 1.016)
					(thickness 0.1524)
				)
				(justify mirror)
			)
		)
		(duplicate_pad_numbers_are_jumpers no)
		(fp_rect
			(start 0.4318 0.9525)
			(end -0.4318 -0.9525)
			(stroke
				(width 0)
				(type default)
			)
			(fill no)
			(layer "B.CrtYd")
		)
		(fp_rect
			(start 0.4318 0.9525)
			(end -0.4318 -0.9525)
			(stroke
				(width 0)
				(type default)
			)
			(fill no)
			(layer "B.Fab")
		)
		(pad "1" smd custom
			(at 0 -0.4445 270)
			(size 0.1524 0.1524)
			(layers "B.Cu" "B.Mask" "B.Paste")
			(net "P1V8")
			(options
				(clearance outline)
				(anchor circle)
			)
			(primitives
				(gr_poly
					(pts
						(arc
							(start 0.3048 0.2032)
							(mid 0.275042 0.275042)
							(end 0.2032 0.3048)
						)
						(arc
							(start -0.2032 0.3048)
							(mid -0.275042 0.275042)
							(end -0.3048 0.2032)
						)
						(arc
							(start -0.3048 -0.2032)
							(mid -0.275042 -0.275042)
							(end -0.2032 -0.3048)
						)
						(arc
							(start 0.2032 -0.3048)
							(mid 0.275042 -0.275042)
							(end 0.3048 -0.2032)
						)
					)
					(width 0)
					(fill yes)
				)
			)
		)
		(pad "2" smd custom
			(at 0 0.4445 270)
			(size 0.1524 0.1524)
			(layers "B.Cu" "B.Mask" "B.Paste")
			(net "GND")
			(options
				(clearance outline)
				(anchor circle)
			)
			(primitives
				(gr_poly
					(pts
						(arc
							(start 0.3048 0.2032)
							(mid 0.275042 0.275042)
							(end 0.2032 0.3048)
						)
						(arc
							(start -0.2032 0.3048)
							(mid -0.275042 0.275042)
							(end -0.3048 0.2032)
						)
						(arc
							(start -0.3048 -0.2032)
							(mid -0.275042 -0.275042)
							(end -0.2032 -0.3048)
						)
						(arc
							(start 0.2032 -0.3048)
							(mid 0.275042 -0.275042)
							(end 0.3048 -0.2032)
						)
					)
					(width 0)
					(fill yes)
				)
			)
		)
	)
	(footprint ""
		(layer "B.Cu")
		(at 56.091328 -140.151104 -90)
		(property "Reference" "TP68"
			(at 0 0 90)
			(layer "B.SilkS")
			(hide yes)
			(effects
				(font
					(size 1.27 1.27)
				)
				(justify mirror)
			)
		)
		(property "Value" "TPAD28-2-GP"
			(at 0.0127 -1.6637 270)
			(unlocked yes)
			(layer "B.Fab")
			(hide yes)
			(effects
				(font
					(size 1.016 1.016)
					(thickness 0.1524)
				)
				(justify mirror)
			)
		)
		(property "Device Type" "TPAD28"
			(at 0.0127 -3.1877 270)
			(unlocked yes)
			(layer "B.Fab")
			(hide yes)
			(effects
				(font
					(size 1.016 1.016)
					(thickness 0.1524)
				)
				(justify mirror)
			)
		)
		(duplicate_pad_numbers_are_jumpers no)
		(fp_poly
			(pts
				(arc
					(start 0 -0.3556)
					(mid 0 0.3556)
					(end 0 -0.3556)
				)
			)
			(stroke
				(width 0)
				(type default)
			)
			(fill no)
			(layer "B.CrtYd")
		)
		(fp_poly
			(pts
				(arc
					(start 0 -0.6096)
					(mid 0 0.6096)
					(end 0 -0.6096)
				)
			)
			(stroke
				(width 0)
				(type default)
			)
			(fill no)
			(layer "B.Fab")
		)
		(pad "1" smd circle
			(at 0 0 90)
			(size 0.7112 0.7112)
			(layers "B.Cu" "B.Mask" "B.Paste")
			(net "TP_BMC_GPIOG5")
		)
	)
	(footprint ""
		(layer "B.Cu")
		(at 197.9168 -55.3974 90)
		(property "Reference" "C435"
			(at 0 0 90)
			(layer "B.SilkS")
			(hide yes)
			(effects
				(font
					(size 1.27 1.27)
				)
				(justify mirror)
			)
		)
		(property "Value" "SCD1U16V2KX-3GP"
			(at -1.1811 -2.7051 90)
			(unlocked yes)
			(layer "B.Fab")
			(hide yes)
			(effects
				(font
					(size 1.016 1.016)
					(thickness 0.1524)
				)
				(justify mirror)
			)
		)
		(property "Device Type" "C402H22"
			(at -1.1811 -4.2291 90)
			(unlocked yes)
			(layer "B.Fab")
			(hide yes)
			(effects
				(font
					(size 1.016 1.016)
					(thickness 0.1524)
				)
				(justify mirror)
			)
		)
		(duplicate_pad_numbers_are_jumpers no)
		(fp_rect
			(start 0.4318 0.9525)
			(end -0.4318 -0.9525)
			(stroke
				(width 0)
				(type default)
			)
			(fill no)
			(layer "B.CrtYd")
		)
		(fp_rect
			(start 0.4318 0.9525)
			(end -0.4318 -0.9525)
			(stroke
				(width 0)
				(type default)
			)
			(fill no)
			(layer "B.Fab")
		)
		(pad "1" smd custom
			(at 0 -0.4445 270)
			(size 0.1524 0.1524)
			(layers "B.Cu" "B.Mask" "B.Paste")
			(net "P1V8")
			(options
				(clearance outline)
				(anchor circle)
			)
			(primitives
				(gr_poly
					(pts
						(arc
							(start 0.3048 0.2032)
							(mid 0.275042 0.275042)
							(end 0.2032 0.3048)
						)
						(arc
							(start -0.2032 0.3048)
							(mid -0.275042 0.275042)
							(end -0.3048 0.2032)
						)
						(arc
							(start -0.3048 -0.2032)
							(mid -0.275042 -0.275042)
							(end -0.2032 -0.3048)
						)
						(arc
							(start 0.2032 -0.3048)
							(mid 0.275042 -0.275042)
							(end 0.3048 -0.2032)
						)
					)
					(width 0)
					(fill yes)
				)
			)
		)
		(pad "2" smd custom
			(at 0 0.4445 270)
			(size 0.1524 0.1524)
			(layers "B.Cu" "B.Mask" "B.Paste")
			(net "GND")
			(options
				(clearance outline)
				(anchor circle)
			)
			(primitives
				(gr_poly
					(pts
						(arc
							(start 0.3048 0.2032)
							(mid 0.275042 0.275042)
							(end 0.2032 0.3048)
						)
						(arc
							(start -0.2032 0.3048)
							(mid -0.275042 0.275042)
							(end -0.3048 0.2032)
						)
						(arc
							(start -0.3048 -0.2032)
							(mid -0.275042 -0.275042)
							(end -0.2032 -0.3048)
						)
						(arc
							(start 0.2032 -0.3048)
							(mid 0.275042 -0.275042)
							(end 0.3048 -0.2032)
						)
					)
					(width 0)
					(fill yes)
				)
			)
		)
	)
	(footprint ""
		(layer "B.Cu")
		(at 204.8256 -65.3542)
		(property "Reference" "TP155"
			(at 0 0 0)
			(layer "B.SilkS")
			(hide yes)
			(effects
				(font
					(size 1.27 1.27)
				)
				(justify mirror)
			)
		)
		(property "Value" "TPAD28-2-GP"
			(at 0.0127 -1.6637 0)
			(unlocked yes)
			(layer "B.Fab")
			(hide yes)
			(effects
				(font
					(size 1.016 1.016)
					(thickness 0.1524)
				)
				(justify mirror)
			)
		)
		(property "Device Type" "TPAD28"
			(at 0.0127 -3.1877 0)
			(unlocked yes)
			(layer "B.Fab")
			(hide yes)
			(effects
				(font
					(size 1.016 1.016)
					(thickness 0.1524)
				)
				(justify mirror)
			)
		)
		(duplicate_pad_numbers_are_jumpers no)
		(fp_poly
			(pts
				(arc
					(start 0.3556 0)
					(mid -0.3556 0)
					(end 0.3556 0)
				)
			)
			(stroke
				(width 0)
				(type default)
			)
			(fill no)
			(layer "B.CrtYd")
		)
		(fp_poly
			(pts
				(arc
					(start 0.6096 0)
					(mid -0.6096 0)
					(end 0.6096 0)
				)
			)
			(stroke
				(width 0)
				(type default)
			)
			(fill no)
			(layer "B.Fab")
		)
		(pad "1" smd circle
			(at 0 0 180)
			(size 0.7112 0.7112)
			(layers "B.Cu" "B.Mask" "B.Paste")
			(net "OSC_REF_CLK")
		)
	)
	(footprint ""
		(layer "B.Cu")
		(at 183.2356 -71.12 180)
		(property "Reference" "C468"
			(at 0 0 0)
			(layer "B.SilkS")
			(hide yes)
			(effects
				(font
					(size 1.27 1.27)
				)
				(justify mirror)
			)
		)
		(property "Value" "SCD1U16V2KX-3GP"
			(at -1.1811 -2.7051 180)
			(unlocked yes)
			(layer "B.Fab")
			(hide yes)
			(effects
				(font
					(size 1.016 1.016)
					(thickness 0.1524)
				)
				(justify mirror)
			)
		)
		(property "Device Type" "C402H22"
			(at -1.1811 -4.2291 180)
			(unlocked yes)
			(layer "B.Fab")
			(hide yes)
			(effects
				(font
					(size 1.016 1.016)
					(thickness 0.1524)
				)
				(justify mirror)
			)
		)
		(duplicate_pad_numbers_are_jumpers no)
		(fp_rect
			(start 0.4318 0.9525)
			(end -0.4318 -0.9525)
			(stroke
				(width 0)
				(type default)
			)
			(fill no)
			(layer "B.CrtYd")
		)
		(fp_rect
			(start 0.4318 0.9525)
			(end -0.4318 -0.9525)
			(stroke
				(width 0)
				(type default)
			)
			(fill no)
			(layer "B.Fab")
		)
		(pad "1" smd custom
			(at 0 -0.4445)
			(size 0.1524 0.1524)
			(layers "B.Cu" "B.Mask" "B.Paste")
			(net "P1V8")
			(options
				(clearance outline)
				(anchor circle)
			)
			(primitives
				(gr_poly
					(pts
						(arc
							(start 0.3048 0.2032)
							(mid 0.275042 0.275042)
							(end 0.2032 0.3048)
						)
						(arc
							(start -0.2032 0.3048)
							(mid -0.275042 0.275042)
							(end -0.3048 0.2032)
						)
						(arc
							(start -0.3048 -0.2032)
							(mid -0.275042 -0.275042)
							(end -0.2032 -0.3048)
						)
						(arc
							(start 0.2032 -0.3048)
							(mid 0.275042 -0.275042)
							(end 0.3048 -0.2032)
						)
					)
					(width 0)
					(fill yes)
				)
			)
		)
		(pad "2" smd custom
			(at 0 0.4445)
			(size 0.1524 0.1524)
			(layers "B.Cu" "B.Mask" "B.Paste")
			(net "GND")
			(options
				(clearance outline)
				(anchor circle)
			)
			(primitives
				(gr_poly
					(pts
						(arc
							(start 0.3048 0.2032)
							(mid 0.275042 0.275042)
							(end 0.2032 0.3048)
						)
						(arc
							(start -0.2032 0.3048)
							(mid -0.275042 0.275042)
							(end -0.3048 0.2032)
						)
						(arc
							(start -0.3048 -0.2032)
							(mid -0.275042 -0.275042)
							(end -0.2032 -0.3048)
						)
						(arc
							(start 0.2032 -0.3048)
							(mid 0.275042 -0.275042)
							(end 0.3048 -0.2032)
						)
					)
					(width 0)
					(fill yes)
				)
			)
		)
	)
)
